(kicad_pcb
	(version 20260206)
	(generator "pcbnew")
	(generator_version "10.0")
	(general
		(thickness 1.6)
		(legacy_teardrops no)
	)
	(paper "A4")
	(title_block
		(title "pdpb — Lightning_PDPB_BRD.brd")
		(comment 1 "Lightning (Wiwynn / Facebook NVMe JBOF) / footprints 264-267 of 1140")
	)
	(layers
		(0 "F.Cu" signal "TOP")
		(4 "In1.Cu" signal "L2GND")
		(6 "In2.Cu" signal "L3")
		(8 "In3.Cu" signal "L4VCC")
		(10 "In4.Cu" signal "L5VCC")
		(12 "In5.Cu" signal "L6")
		(14 "In6.Cu" signal "L7GND")
		(2 "B.Cu" signal "BOTTOM")
		(9 "F.Adhes" user "F.Adhesive")
		(11 "B.Adhes" user "B.Adhesive")
		(13 "F.Paste" user "Package Geometry/Pastemask Top")
		(15 "B.Paste" user "Package Geometry/Pastemask Bottom")
		(5 "F.SilkS" user "Ref Des/Silkscreen Top")
		(7 "B.SilkS" user "Ref Des/Silkscreen Bottom")
		(1 "F.Mask" user "Board Geometry/Soldermask Top")
		(3 "B.Mask" user "Board Geometry/Soldermask Bottom")
		(17 "Dwgs.User" user "User.Drawings")
		(19 "Cmts.User" user "User.Comments")
		(21 "Eco1.User" user "User.Eco1")
		(23 "Eco2.User" user "User.Eco2")
		(25 "Edge.Cuts" user "Board Geometry/Outline")
		(27 "Margin" user)
		(31 "F.CrtYd" user "Package Geometry/Place Bound Top")
		(29 "B.CrtYd" user "Package Geometry/Place Bound Bottom")
		(35 "F.Fab" user "Ref Des/Assembly Top")
		(33 "B.Fab" user "Ref Des/Assembly Bottom")
	)
	(footprint ""
		(layer "F.Cu")
		(at 21.017992 -370.877592 180)
		(property "Reference" "C9529"
			(at 0 0 180)
			(layer "F.SilkS")
			(hide yes)
			(effects
				(font
					(size 1.27 1.27)
				)
			)
		)
		(property "Value" "SCD1U16V2KX-3GP"
			(at 1.1811 -2.7051 180)
			(unlocked yes)
			(layer "F.Fab")
			(hide yes)
			(effects
				(font
					(size 1.016 1.016)
					(thickness 0.1524)
				)
			)
		)
		(property "Device Type" "C402H22"
			(at 1.1811 -4.2291 180)
			(unlocked yes)
			(layer "F.Fab")
			(hide yes)
			(effects
				(font
					(size 1.016 1.016)
					(thickness 0.1524)
				)
			)
		)
		(duplicate_pad_numbers_are_jumpers no)
		(fp_rect
			(start -0.4318 0.9525)
			(end 0.4318 -0.9525)
			(stroke
				(width 0)
				(type default)
			)
			(fill no)
			(layer "F.CrtYd")
		)
		(fp_rect
			(start -0.4318 0.9525)
			(end 0.4318 -0.9525)
			(stroke
				(width 0)
				(type default)
			)
			(fill no)
			(layer "F.Fab")
		)
		(pad "1" smd custom
			(at 0 -0.4445 180)
			(size 0.1524 0.1524)
			(layers "F.Cu" "F.Mask" "F.Paste")
			(net "P3V3")
			(options
				(clearance outline)
				(anchor circle)
			)
			(primitives
				(gr_poly
					(pts
						(arc
							(start 0.3048 -0.2032)
							(mid 0.275042 -0.275042)
							(end 0.2032 -0.3048)
						)
						(arc
							(start -0.2032 -0.3048)
							(mid -0.275042 -0.275042)
							(end -0.3048 -0.2032)
						)
						(arc
							(start -0.3048 0.2032)
							(mid -0.275042 0.275042)
							(end -0.2032 0.3048)
						)
						(arc
							(start 0.2032 0.3048)
							(mid 0.275042 0.275042)
							(end 0.3048 0.2032)
						)
					)
					(width 0)
					(fill yes)
				)
			)
		)
		(pad "2" smd custom
			(at 0 0.4445 180)
			(size 0.1524 0.1524)
			(layers "F.Cu" "F.Mask" "F.Paste")
			(net "GND")
			(options
				(clearance outline)
				(anchor circle)
			)
			(primitives
				(gr_poly
					(pts
						(arc
							(start 0.3048 -0.2032)
							(mid 0.275042 -0.275042)
							(end 0.2032 -0.3048)
						)
						(arc
							(start -0.2032 -0.3048)
							(mid -0.275042 -0.275042)
							(end -0.3048 -0.2032)
						)
						(arc
							(start -0.3048 0.2032)
							(mid -0.275042 0.275042)
							(end -0.2032 0.3048)
						)
						(arc
							(start 0.2032 0.3048)
							(mid 0.275042 0.275042)
							(end 0.3048 0.2032)
						)
					)
					(width 0)
					(fill yes)
				)
			)
		)
	)
	(footprint ""
		(layer "F.Cu")
		(at 38.9128 -315.8744 180)
		(property "Reference" "R562"
			(at 0 0 180)
			(layer "F.SilkS")
			(hide yes)
			(effects
				(font
					(size 1.27 1.27)
				)
			)
		)
		(property "Value" "200KR2F-L-GP"
			(at 0.064008 -3.993896 180)
			(unlocked yes)
			(layer "F.Fab")
			(hide yes)
			(effects
				(font
					(size 1.016 1.016)
					(thickness 0.1524)
				)
			)
		)
		(property "Device Type" "R402H16"
			(at 0.064008 -5.517896 180)
			(unlocked yes)
			(layer "F.Fab")
			(hide yes)
			(effects
				(font
					(size 1.016 1.016)
					(thickness 0.1524)
				)
			)
		)
		(duplicate_pad_numbers_are_jumpers no)
		(fp_line
			(start 0.508 -0.9398)
			(end -0.508 -0.9398)
			(stroke
				(width 0.1524)
				(type default)
			)
			(layer "F.SilkS")
		)
		(fp_line
			(start -0.508 -0.9398)
			(end -0.508 0.9398)
			(stroke
				(width 0.1524)
				(type default)
			)
			(layer "F.SilkS")
		)
		(fp_rect
			(start -0.508 0.9398)
			(end 0.508 -0.9398)
			(stroke
				(width 0)
				(type default)
			)
			(fill no)
			(layer "F.CrtYd")
		)
		(fp_rect
			(start -0.508 0.9398)
			(end 0.508 -0.9398)
			(stroke
				(width 0)
				(type default)
			)
			(fill no)
			(layer "F.Fab")
		)
		(pad "1" smd custom
			(at 0 -0.4445 180)
			(size 0.1397 0.1397)
			(layers "F.Cu" "F.Mask" "F.Paste")
			(net "SW_SSD11_R")
			(options
				(clearance outline)
				(anchor circle)
			)
			(primitives
				(gr_poly
					(pts
						(arc
							(start -0.1778 -0.2794)
							(mid -0.249642 -0.249642)
							(end -0.2794 -0.1778)
						)
						(arc
							(start -0.2794 0.1778)
							(mid -0.249642 0.249642)
							(end -0.1778 0.2794)
						)
						(arc
							(start 0.1778 0.2794)
							(mid 0.249642 0.249642)
							(end 0.2794 0.1778)
						)
						(arc
							(start 0.2794 -0.1778)
							(mid 0.249642 -0.249642)
							(end 0.1778 -0.2794)
						)
					)
					(width 0)
					(fill yes)
				)
			)
		)
		(pad "2" smd custom
			(at 0 0.4445 180)
			(size 0.1397 0.1397)
			(layers "F.Cu" "F.Mask" "F.Paste")
			(net "SW_SSD11_N")
			(options
				(clearance outline)
				(anchor circle)
			)
			(primitives
				(gr_poly
					(pts
						(arc
							(start -0.1778 -0.2794)
							(mid -0.249642 -0.249642)
							(end -0.2794 -0.1778)
						)
						(arc
							(start -0.2794 0.1778)
							(mid -0.249642 0.249642)
							(end -0.1778 0.2794)
						)
						(arc
							(start 0.1778 0.2794)
							(mid 0.249642 0.249642)
							(end 0.2794 0.1778)
						)
						(arc
							(start 0.2794 -0.1778)
							(mid 0.249642 -0.249642)
							(end 0.1778 -0.2794)
						)
					)
					(width 0)
					(fill yes)
				)
			)
		)
	)
	(footprint ""
		(layer "F.Cu")
		(at 234.061 -142.494 -90)
		(property "Reference" "R9895"
			(at 0 0 270)
			(layer "F.SilkS")
			(hide yes)
			(effects
				(font
					(size 1.27 1.27)
				)
			)
		)
		(property "Value" "1K82R2F-1-GP"
			(at 0.064008 -3.993896 270)
			(unlocked yes)
			(layer "F.Fab")
			(hide yes)
			(effects
				(font
					(size 1.016 1.016)
					(thickness 0.1524)
				)
			)
		)
		(property "Device Type" "R402H16"
			(at 0.064008 -5.517896 270)
			(unlocked yes)
			(layer "F.Fab")
			(hide yes)
			(effects
				(font
					(size 1.016 1.016)
					(thickness 0.1524)
				)
			)
		)
		(duplicate_pad_numbers_are_jumpers no)
		(fp_line
			(start -0.508 -0.9398)
			(end -0.508 0.9398)
			(stroke
				(width 0.1524)
				(type default)
			)
			(layer "F.SilkS")
		)
		(fp_line
			(start 0.508 -0.9398)
			(end -0.508 -0.9398)
			(stroke
				(width 0.1524)
				(type default)
			)
			(layer "F.SilkS")
		)
		(fp_rect
			(start -0.508 0.9398)
			(end 0.508 -0.9398)
			(stroke
				(width 0)
				(type default)
			)
			(fill no)
			(layer "F.CrtYd")
		)
		(fp_rect
			(start -0.508 0.9398)
			(end 0.508 -0.9398)
			(stroke
				(width 0)
				(type default)
			)
			(fill no)
			(layer "F.Fab")
		)
		(pad "1" smd custom
			(at 0 -0.4445 270)
			(size 0.1397 0.1397)
			(layers "F.Cu" "F.Mask" "F.Paste")
			(net "P12V")
			(options
				(clearance outline)
				(anchor circle)
			)
			(primitives
				(gr_poly
					(pts
						(arc
							(start -0.1778 -0.2794)
							(mid -0.249642 -0.249642)
							(end -0.2794 -0.1778)
						)
						(arc
							(start -0.2794 0.1778)
							(mid -0.249642 0.249642)
							(end -0.1778 0.2794)
						)
						(arc
							(start 0.1778 0.2794)
							(mid 0.249642 0.249642)
							(end 0.2794 0.1778)
						)
						(arc
							(start 0.2794 -0.1778)
							(mid 0.249642 -0.249642)
							(end 0.1778 -0.2794)
						)
					)
					(width 0)
					(fill yes)
				)
			)
		)
		(pad "2" smd custom
			(at 0 0.4445 270)
			(size 0.1397 0.1397)
			(layers "F.Cu" "F.Mask" "F.Paste")
			(net "DRV_ACT_3")
			(options
				(clearance outline)
				(anchor circle)
			)
			(primitives
				(gr_poly
					(pts
						(arc
							(start -0.1778 -0.2794)
							(mid -0.249642 -0.249642)
							(end -0.2794 -0.1778)
						)
						(arc
							(start -0.2794 0.1778)
							(mid -0.249642 0.249642)
							(end -0.1778 0.2794)
						)
						(arc
							(start 0.1778 0.2794)
							(mid 0.249642 0.249642)
							(end 0.2794 0.1778)
						)
						(arc
							(start 0.2794 -0.1778)
							(mid 0.249642 -0.249642)
							(end 0.1778 -0.2794)
						)
					)
					(width 0)
					(fill yes)
				)
			)
		)
	)
	(footprint ""
		(layer "F.Cu")
		(at 212.217 -439.674 180)
		(property "Reference" "PC1272"
			(at 0 0 180)
			(layer "F.SilkS")
			(hide yes)
			(effects
				(font
					(size 1.27 1.27)
				)
			)
		)
		(property "Value" "SC22U6D3V5MX-5-GP"
			(at -0.0762 -6.1214 180)
			(unlocked yes)
			(layer "F.Fab")
			(hide yes)
			(effects
				(font
					(size 1.016 1.016)
					(thickness 0.1524)
				)
			)
		)
		(property "Device Type" "C805H56"
			(at -0.0762 -8.1534 180)
			(unlocked yes)
			(layer "F.Fab")
			(hide yes)
			(effects
				(font
					(size 1.016 1.016)
					(thickness 0.1524)
				)
			)
		)
		(duplicate_pad_numbers_are_jumpers no)
		(fp_line
			(start 0.635 0)
			(end -0.635 0)
			(stroke
				(width 0.508)
				(type default)
			)
			(layer "F.SilkS")
		)
		(fp_rect
			(start -0.9652 1.778)
			(end 0.9652 -1.778)
			(stroke
				(width 0)
				(type default)
			)
			(fill no)
			(layer "F.CrtYd")
		)
		(fp_poly
			(pts
				(xy -0.9652 -1.778) (xy 0.9652 -1.778) (xy 0.9652 1.778) (xy -0.9652 1.778)
			)
			(stroke
				(width 0)
				(type default)
			)
			(fill no)
			(layer "F.Fab")
		)
		(pad "1" smd rect
			(at 0 -0.9652 180)
			(size 1.397 1.143)
			(layers "F.Cu" "F.Mask" "F.Paste")
			(net "P3V3_OUT")
		)
		(pad "2" smd rect
			(at 0 0.9652 180)
			(size 1.397 1.143)
			(layers "F.Cu" "F.Mask" "F.Paste")
			(net "GND")
		)
	)
)
